(kicad_pcb
	(version 20260206)
	(generator "pcbnew")
	(generator_version "10.0")
	(general
		(thickness 1.6)
		(legacy_teardrops no)
	)
	(paper "A4")
	(title_block
		(title "baseboard — 13948-1b.1110WZS1818.brd")
		(comment 1 "Honey Badger (Wiwynn) / footprints 21-25 of 2523")
	)
	(layers
		(0 "F.Cu" signal "TOP")
		(4 "In1.Cu" signal "L2GND")
		(6 "In2.Cu" signal "L3")
		(8 "In3.Cu" signal "L4VCC")
		(10 "In4.Cu" signal "L5VCC")
		(12 "In5.Cu" signal "L6")
		(14 "In6.Cu" signal "L7GND")
		(2 "B.Cu" signal "BOTTOM")
		(9 "F.Adhes" user "F.Adhesive")
		(11 "B.Adhes" user "B.Adhesive")
		(13 "F.Paste" user "Package Geometry/Pastemask Top")
		(15 "B.Paste" user "Package Geometry/Pastemask Bottom")
		(5 "F.SilkS" user "Ref Des/Silkscreen Top")
		(7 "B.SilkS" user "Ref Des/Silkscreen Bottom")
		(1 "F.Mask" user "Board Geometry/Soldermask Top")
		(3 "B.Mask" user "Board Geometry/Soldermask Bottom")
		(17 "Dwgs.User" user "User.Drawings")
		(19 "Cmts.User" user "User.Comments")
		(21 "Eco1.User" user "User.Eco1")
		(23 "Eco2.User" user "User.Eco2")
		(25 "Edge.Cuts" user "Board Geometry/Outline")
		(27 "Margin" user)
		(31 "F.CrtYd" user "Package Geometry/Place Bound Top")
		(29 "B.CrtYd" user "Package Geometry/Place Bound Bottom")
		(35 "F.Fab" user "Ref Des/Assembly Top")
		(33 "B.Fab" user "Ref Des/Assembly Bottom")
	)
	(footprint ""
		(layer "F.Cu")
		(at 190.300102 -258.59994 180)
		(property "Reference" "GF7"
			(at 0 0 180)
			(layer "F.SilkS")
			(hide yes)
			(effects
				(font
					(size 1.27 1.27)
				)
			)
		)
		(property "Value" "GF-PCIE-36P-GP"
			(at -5.118354 -8.09879 180)
			(unlocked yes)
			(layer "F.Fab")
			(hide yes)
			(effects
				(font
					(size 1.016 1.016)
					(thickness 0.1524)
				)
			)
		)
		(property "Device Type" "GF-PCIE-36P"
			(at -5.118354 -9.62279 180)
			(unlocked yes)
			(layer "F.Fab")
			(hide yes)
			(effects
				(font
					(size 1.016 1.016)
					(thickness 0.1524)
				)
			)
		)
		(duplicate_pad_numbers_are_jumpers no)
		(fp_rect
			(start -13.8811 2.032)
			(end 9.8933 -6.223)
			(stroke
				(width 0)
				(type default)
			)
			(fill no)
			(layer "B.CrtYd")
		)
		(fp_rect
			(start -13.8811 2.032)
			(end 9.8933 -6.223)
			(stroke
				(width 0)
				(type default)
			)
			(fill no)
			(layer "F.CrtYd")
		)
		(fp_rect
			(start -13.8811 2.032)
			(end 9.8933 -6.223)
			(stroke
				(width 0)
				(type default)
			)
			(fill no)
			(layer "B.Fab")
		)
		(fp_rect
			(start -13.8811 2.032)
			(end 9.8933 -6.223)
			(stroke
				(width 0)
				(type default)
			)
			(fill no)
			(layer "F.Fab")
		)
		(fp_text user "02 Do not mirror"
			(at -10.94613 2.91084 180)
			(unlocked yes)
			(layer "F.Fab")
			(effects
				(font
					(size 1.016 1.016)
					(thickness 0.1524)
				)
				(justify left)
			)
		)
		(pad "A1" smd rect
			(at -11.49985 -2.0955 180)
			(size 0.7112 3.2004)
			(drill
				(offset 0 -0.4953)
			)
			(layers "F.Cu" "F.Mask" "F.Paste")
			(net "PCIE_MATED#_B")
		)
		(pad "A2" smd rect
			(at -10.50036 -2.0955 180)
			(size 0.7112 4.191)
			(layers "F.Cu" "F.Mask" "F.Paste")
			(net "P12V_PCIE")
		)
		(pad "A3" smd rect
			(at -9.4996 -2.0955 180)
			(size 0.7112 4.191)
			(layers "F.Cu" "F.Mask" "F.Paste")
			(net "P12V_PCIE")
		)
		(pad "A4" smd rect
			(at -8.50011 -2.0955 180)
			(size 0.7112 4.191)
			(layers "F.Cu" "F.Mask" "F.Paste")
			(net "P12V_PCIE")
		)
		(pad "A5" smd rect
			(at -7.49935 -2.0955 180)
			(size 0.7112 4.191)
			(layers "F.Cu" "F.Mask" "F.Paste")
			(net "P12V_PCIE")
		)
		(pad "A6" smd rect
			(at -6.49986 -2.0955 180)
			(size 0.7112 4.191)
			(layers "F.Cu" "F.Mask" "F.Paste")
			(net "P12V_PCIE")
		)
		(pad "A7" smd rect
			(at -5.50037 -2.0955 180)
			(size 0.7112 4.191)
			(layers "F.Cu" "F.Mask" "F.Paste")
			(net "P12V_PCIE")
		)
		(pad "A8" smd rect
			(at -4.49961 -2.0955 180)
			(size 0.7112 4.191)
			(layers "F.Cu" "F.Mask" "F.Paste")
			(net "P12V_PCIE")
		)
		(pad "A9" smd rect
			(at -3.50012 -2.0955 180)
			(size 0.7112 4.191)
			(layers "F.Cu" "F.Mask" "F.Paste")
			(net "Net_208")
		)
		(pad "A10" smd rect
			(at -2.49936 -2.0955 180)
			(size 0.7112 4.191)
			(layers "F.Cu" "F.Mask" "F.Paste")
			(net "Net_209")
		)
		(pad "A11" smd rect
			(at -1.49987 -2.0955 180)
			(size 0.7112 4.191)
			(layers "F.Cu" "F.Mask" "F.Paste")
			(net "Net_210")
		)
		(pad "A12" smd rect
			(at 1.49987 -2.0955 180)
			(size 0.7112 4.191)
			(layers "F.Cu" "F.Mask" "F.Paste")
			(net "Net_196")
		)
		(pad "A13" smd rect
			(at 2.50063 -2.0955 180)
			(size 0.7112 4.191)
			(layers "F.Cu" "F.Mask" "F.Paste")
			(net "GND")
		)
		(pad "A14" smd rect
			(at 3.50012 -2.0955 180)
			(size 0.7112 4.191)
			(layers "F.Cu" "F.Mask" "F.Paste")
			(net "Net_197")
		)
		(pad "A15" smd rect
			(at 4.49961 -2.0955 180)
			(size 0.7112 4.191)
			(layers "F.Cu" "F.Mask" "F.Paste")
			(net "Net_198")
		)
		(pad "A16" smd rect
			(at 5.50037 -2.0955 180)
			(size 0.7112 4.191)
			(layers "F.Cu" "F.Mask" "F.Paste")
			(net "GND")
		)
		(pad "A17" smd rect
			(at 6.49986 -2.0955 180)
			(size 0.7112 4.191)
			(layers "F.Cu" "F.Mask" "F.Paste")
			(net "Net_199")
		)
		(pad "A18" smd rect
			(at 7.50062 -2.0955 180)
			(size 0.7112 4.191)
			(layers "F.Cu" "F.Mask" "F.Paste")
			(net "GND")
		)
		(pad "B1" smd rect
			(at -11.49985 -2.3495 180)
			(size 0.7112 4.191)
			(drill
				(offset 0 0.254)
			)
			(layers "F.Cu" "F.Mask" "F.Paste")
			(net "GND")
		)
		(pad "B2" smd rect
			(at -10.50036 -2.3495 180)
			(size 0.7112 4.191)
			(drill
				(offset 0 0.254)
			)
			(layers "F.Cu" "F.Mask" "F.Paste")
			(net "GND")
		)
		(pad "B3" smd rect
			(at -9.4996 -2.3495 180)
			(size 0.7112 4.191)
			(drill
				(offset 0 0.254)
			)
			(layers "F.Cu" "F.Mask" "F.Paste")
			(net "GND")
		)
		(pad "B4" smd rect
			(at -8.50011 -2.3495 180)
			(size 0.7112 4.191)
			(drill
				(offset 0 0.254)
			)
			(layers "F.Cu" "F.Mask" "F.Paste")
			(net "GND")
		)
		(pad "B5" smd rect
			(at -7.49935 -2.3495 180)
			(size 0.7112 4.191)
			(drill
				(offset 0 0.254)
			)
			(layers "F.Cu" "F.Mask" "F.Paste")
			(net "GND")
		)
		(pad "B6" smd rect
			(at -6.49986 -2.3495 180)
			(size 0.7112 4.191)
			(drill
				(offset 0 0.254)
			)
			(layers "F.Cu" "F.Mask" "F.Paste")
			(net "GND")
		)
		(pad "B7" smd rect
			(at -5.50037 -2.3495 180)
			(size 0.7112 4.191)
			(drill
				(offset 0 0.254)
			)
			(layers "F.Cu" "F.Mask" "F.Paste")
			(net "GND")
		)
		(pad "B8" smd rect
			(at -4.49961 -2.3495 180)
			(size 0.7112 4.191)
			(drill
				(offset 0 0.254)
			)
			(layers "F.Cu" "F.Mask" "F.Paste")
			(net "Net_205")
		)
		(pad "B9" smd rect
			(at -3.50012 -2.3495 180)
			(size 0.7112 4.191)
			(drill
				(offset 0 0.254)
			)
			(layers "F.Cu" "F.Mask" "F.Paste")
			(net "Net_206")
		)
		(pad "B10" smd rect
			(at -2.49936 -2.3495 180)
			(size 0.7112 4.191)
			(drill
				(offset 0 0.254)
			)
			(layers "F.Cu" "F.Mask" "F.Paste")
			(net "Net_207")
		)
		(pad "B11" smd rect
			(at -1.49987 -2.3495 180)
			(size 0.7112 4.191)
			(drill
				(offset 0 0.254)
			)
			(layers "F.Cu" "F.Mask" "F.Paste")
			(net "Net_204")
		)
		(pad "B12" smd rect
			(at 1.49987 -2.3495 180)
			(size 0.7112 4.191)
			(drill
				(offset 0 0.254)
			)
			(layers "F.Cu" "F.Mask" "F.Paste")
			(net "GND")
		)
		(pad "B13" smd rect
			(at 2.50063 -2.3495 180)
			(size 0.7112 4.191)
			(drill
				(offset 0 0.254)
			)
			(layers "F.Cu" "F.Mask" "F.Paste")
			(net "Net_200")
		)
		(pad "B14" smd rect
			(at 3.50012 -2.3495 180)
			(size 0.7112 4.191)
			(drill
				(offset 0 0.254)
			)
			(layers "F.Cu" "F.Mask" "F.Paste")
			(net "Net_201")
		)
		(pad "B15" smd rect
			(at 4.49961 -2.3495 180)
			(size 0.7112 4.191)
			(drill
				(offset 0 0.254)
			)
			(layers "F.Cu" "F.Mask" "F.Paste")
			(net "GND")
		)
		(pad "B16" smd rect
			(at 5.50037 -2.3495 180)
			(size 0.7112 4.191)
			(drill
				(offset 0 0.254)
			)
			(layers "F.Cu" "F.Mask" "F.Paste")
			(net "Net_202")
		)
		(pad "B17" smd rect
			(at 6.49986 -2.3495 180)
			(size 0.7112 3.2004)
			(drill
				(offset 0 -0.2413)
			)
			(layers "F.Cu" "F.Mask" "F.Paste")
			(net "Net_203")
		)
		(pad "B18" smd rect
			(at 7.50062 -2.3495 180)
			(size 0.7112 4.191)
			(drill
				(offset 0 0.254)
			)
			(layers "F.Cu" "F.Mask" "F.Paste")
			(net "GND")
		)
		(zone
			(layer "F.Cu")
			(hatch none 0.5)
			(connect_pads
				(clearance 0)
			)
			(min_thickness 0.25)
			(keepout
				(tracks allowed)
				(vias not_allowed)
				(pads allowed)
				(copperpour not_allowed)
				(footprints allowed)
			)
			(placement
				(enabled no)
				(sheetname "")
			)
			(fill
				(thermal_gap 0.5)
				(thermal_bridge_width 0.5)
				(island_removal_mode 0)
			)
			(polygon
				(pts
					(xy 203.170282 -259.61594) (xy 181.427882 -259.61594) (xy 181.427882 -253.39294) (xy 203.170282 -253.39294)
				)
			)
		)
		(zone
			(layer "F.Cu")
			(hatch none 0.5)
			(connect_pads
				(clearance 0)
			)
			(min_thickness 0.25)
			(keepout
				(tracks not_allowed)
				(vias allowed)
				(pads allowed)
				(copperpour not_allowed)
				(footprints allowed)
			)
			(placement
				(enabled no)
				(sheetname "")
			)
			(fill
				(thermal_gap 0.5)
				(thermal_bridge_width 0.5)
				(island_removal_mode 0)
			)
			(polygon
				(pts
					(xy 203.170282 -258.59994) (xy 203.170282 -259.61594) (xy 181.427882 -259.61594) (xy 181.427882 -258.59994)
				)
			)
		)
		(zone
			(layer "B.Cu")
			(hatch none 0.5)
			(connect_pads
				(clearance 0)
			)
			(min_thickness 0.25)
			(keepout
				(tracks not_allowed)
				(vias allowed)
				(pads allowed)
				(copperpour not_allowed)
				(footprints allowed)
			)
			(placement
				(enabled no)
				(sheetname "")
			)
			(fill
				(thermal_gap 0.5)
				(thermal_bridge_width 0.5)
				(island_removal_mode 0)
			)
			(polygon
				(pts
					(xy 203.170282 -259.61594) (xy 181.427882 -259.61594) (xy 181.427882 -258.59994) (xy 203.170282 -258.59994)
				)
			)
		)
		(zone
			(layer "B.Cu")
			(hatch none 0.5)
			(connect_pads
				(clearance 0)
			)
			(min_thickness 0.25)
			(keepout
				(tracks allowed)
				(vias not_allowed)
				(pads allowed)
				(copperpour not_allowed)
				(footprints allowed)
			)
			(placement
				(enabled no)
				(sheetname "")
			)
			(fill
				(thermal_gap 0.5)
				(thermal_bridge_width 0.5)
				(island_removal_mode 0)
			)
			(polygon
				(pts
					(xy 203.170282 -259.61594) (xy 181.427882 -259.61594) (xy 181.427882 -253.39294) (xy 203.170282 -253.39294)
				)
			)
		)
	)
	(footprint ""
		(layer "F.Cu")
		(at 349.123 -108.204)
		(property "Reference" "PC8"
			(at 0 0 0)
			(layer "F.SilkS")
			(hide yes)
			(effects
				(font
					(size 1.27 1.27)
				)
			)
		)
		(property "Value" "SC22U25V5MX-GP"
			(at -0.0762 -6.1214 0)
			(unlocked yes)
			(layer "F.Fab")
			(hide yes)
			(effects
				(font
					(size 1.016 1.016)
					(thickness 0.1524)
				)
			)
		)
		(property "Device Type" "C805H58"
			(at -0.0762 -8.1534 0)
			(unlocked yes)
			(layer "F.Fab")
			(hide yes)
			(effects
				(font
					(size 1.016 1.016)
					(thickness 0.1524)
				)
			)
		)
		(duplicate_pad_numbers_are_jumpers no)
		(fp_line
			(start 0.635 0)
			(end -0.635 0)
			(stroke
				(width 0.508)
				(type default)
			)
			(layer "F.SilkS")
		)
		(fp_rect
			(start -0.9652 1.778)
			(end 0.9652 -1.778)
			(stroke
				(width 0)
				(type default)
			)
			(fill no)
			(layer "F.CrtYd")
		)
		(fp_poly
			(pts
				(xy -0.9652 -1.778) (xy 0.9652 -1.778) (xy 0.9652 1.778) (xy -0.9652 1.778)
			)
			(stroke
				(width 0)
				(type default)
			)
			(fill no)
			(layer "F.Fab")
		)
		(pad "1" smd rect
			(at 0 -0.9652)
			(size 1.397 1.143)
			(layers "F.Cu" "F.Mask" "F.Paste")
			(net "P5V_STBY_VIN")
		)
		(pad "2" smd rect
			(at 0 0.9652)
			(size 1.397 1.143)
			(layers "F.Cu" "F.Mask" "F.Paste")
			(net "GND")
		)
	)
	(footprint ""
		(layer "F.Cu")
		(at 318.008 -172.72 -90)
		(property "Reference" "R802"
			(at 0 0 270)
			(layer "F.SilkS")
			(hide yes)
			(effects
				(font
					(size 1.27 1.27)
				)
			)
		)
		(property "Value" "4K7R2F-GP"
			(at 0.064008 -3.993896 270)
			(unlocked yes)
			(layer "F.Fab")
			(hide yes)
			(effects
				(font
					(size 1.016 1.016)
					(thickness 0.1524)
				)
			)
		)
		(property "Device Type" "R402H16"
			(at 0.064008 -5.517896 270)
			(unlocked yes)
			(layer "F.Fab")
			(hide yes)
			(effects
				(font
					(size 1.016 1.016)
					(thickness 0.1524)
				)
			)
		)
		(duplicate_pad_numbers_are_jumpers no)
		(fp_line
			(start -0.508 -0.9398)
			(end -0.508 0.9398)
			(stroke
				(width 0.1524)
				(type default)
			)
			(layer "F.SilkS")
		)
		(fp_line
			(start 0.508 -0.9398)
			(end -0.508 -0.9398)
			(stroke
				(width 0.1524)
				(type default)
			)
			(layer "F.SilkS")
		)
		(fp_rect
			(start -0.508 0.9398)
			(end 0.508 -0.9398)
			(stroke
				(width 0)
				(type default)
			)
			(fill no)
			(layer "F.CrtYd")
		)
		(fp_rect
			(start -0.508 0.9398)
			(end 0.508 -0.9398)
			(stroke
				(width 0)
				(type default)
			)
			(fill no)
			(layer "F.Fab")
		)
		(pad "1" smd custom
			(at 0 -0.4445 270)
			(size 0.1397 0.1397)
			(layers "F.Cu" "F.Mask" "F.Paste")
			(net "P3V3_STBY")
			(options
				(clearance outline)
				(anchor circle)
			)
			(primitives
				(gr_poly
					(pts
						(arc
							(start -0.1778 -0.2794)
							(mid -0.249642 -0.249642)
							(end -0.2794 -0.1778)
						)
						(arc
							(start -0.2794 0.1778)
							(mid -0.249642 0.249642)
							(end -0.1778 0.2794)
						)
						(arc
							(start 0.1778 0.2794)
							(mid 0.249642 0.249642)
							(end 0.2794 0.1778)
						)
						(arc
							(start 0.2794 -0.1778)
							(mid 0.249642 -0.249642)
							(end 0.1778 -0.2794)
						)
					)
					(width 0)
					(fill yes)
				)
			)
		)
		(pad "2" smd custom
			(at 0 0.4445 270)
			(size 0.1397 0.1397)
			(layers "F.Cu" "F.Mask" "F.Paste")
			(net "JTAG_BMC_TDI")
			(options
				(clearance outline)
				(anchor circle)
			)
			(primitives
				(gr_poly
					(pts
						(arc
							(start -0.1778 -0.2794)
							(mid -0.249642 -0.249642)
							(end -0.2794 -0.1778)
						)
						(arc
							(start -0.2794 0.1778)
							(mid -0.249642 0.249642)
							(end -0.1778 0.2794)
						)
						(arc
							(start 0.1778 0.2794)
							(mid 0.249642 0.249642)
							(end 0.2794 0.1778)
						)
						(arc
							(start 0.2794 -0.1778)
							(mid 0.249642 -0.249642)
							(end 0.1778 -0.2794)
						)
					)
					(width 0)
					(fill yes)
				)
			)
		)
	)
	(footprint ""
		(layer "F.Cu")
		(at 182.426864 -38.172136 180)
		(property "Reference" "R391"
			(at 0 0 180)
			(layer "F.SilkS")
			(hide yes)
			(effects
				(font
					(size 1.27 1.27)
				)
			)
		)
		(property "Value" "4K75R2F-1-GP"
			(at 0.064008 -3.993896 180)
			(unlocked yes)
			(layer "F.Fab")
			(hide yes)
			(effects
				(font
					(size 1.016 1.016)
					(thickness 0.1524)
				)
			)
		)
		(property "Device Type" "R402H16"
			(at 0.064008 -5.517896 180)
			(unlocked yes)
			(layer "F.Fab")
			(hide yes)
			(effects
				(font
					(size 1.016 1.016)
					(thickness 0.1524)
				)
			)
		)
		(duplicate_pad_numbers_are_jumpers no)
		(fp_line
			(start 0.508 -0.9398)
			(end -0.508 -0.9398)
			(stroke
				(width 0.1524)
				(type default)
			)
			(layer "F.SilkS")
		)
		(fp_line
			(start -0.508 -0.9398)
			(end -0.508 0.9398)
			(stroke
				(width 0.1524)
				(type default)
			)
			(layer "F.SilkS")
		)
		(fp_rect
			(start -0.508 0.9398)
			(end 0.508 -0.9398)
			(stroke
				(width 0)
				(type default)
			)
			(fill no)
			(layer "F.CrtYd")
		)
		(fp_rect
			(start -0.508 0.9398)
			(end 0.508 -0.9398)
			(stroke
				(width 0)
				(type default)
			)
			(fill no)
			(layer "F.Fab")
		)
		(pad "1" smd custom
			(at 0 -0.4445 180)
			(size 0.1397 0.1397)
			(layers "F.Cu" "F.Mask" "F.Paste")
			(net "PHY_AD1")
			(options
				(clearance outline)
				(anchor circle)
			)
			(primitives
				(gr_poly
					(pts
						(arc
							(start -0.1778 -0.2794)
							(mid -0.249642 -0.249642)
							(end -0.2794 -0.1778)
						)
						(arc
							(start -0.2794 0.1778)
							(mid -0.249642 0.249642)
							(end -0.1778 0.2794)
						)
						(arc
							(start 0.1778 0.2794)
							(mid 0.249642 0.249642)
							(end 0.2794 0.1778)
						)
						(arc
							(start 0.2794 -0.1778)
							(mid 0.249642 -0.249642)
							(end 0.1778 -0.2794)
						)
					)
					(width 0)
					(fill yes)
				)
			)
		)
		(pad "2" smd custom
			(at 0 0.4445 180)
			(size 0.1397 0.1397)
			(layers "F.Cu" "F.Mask" "F.Paste")
			(net "GND")
			(options
				(clearance outline)
				(anchor circle)
			)
			(primitives
				(gr_poly
					(pts
						(arc
							(start -0.1778 -0.2794)
							(mid -0.249642 -0.249642)
							(end -0.2794 -0.1778)
						)
						(arc
							(start -0.2794 0.1778)
							(mid -0.249642 0.249642)
							(end -0.1778 0.2794)
						)
						(arc
							(start 0.1778 0.2794)
							(mid 0.249642 0.249642)
							(end 0.2794 0.1778)
						)
						(arc
							(start 0.2794 -0.1778)
							(mid 0.249642 -0.249642)
							(end 0.1778 -0.2794)
						)
					)
					(width 0)
					(fill yes)
				)
			)
		)
	)
	(footprint ""
		(layer "F.Cu")
		(at 318.893952 -58.547 -90)
		(property "Reference" "R213"
			(at 0 0 270)
			(layer "F.SilkS")
			(hide yes)
			(effects
				(font
					(size 1.27 1.27)
				)
			)
		)
		(property "Value" "0R2J-2-GP"
			(at 0.064008 -3.993896 270)
			(unlocked yes)
			(layer "F.Fab")
			(hide yes)
			(effects
				(font
					(size 1.016 1.016)
					(thickness 0.1524)
				)
			)
		)
		(property "Device Type" "R402H16"
			(at 0.064008 -5.517896 270)
			(unlocked yes)
			(layer "F.Fab")
			(hide yes)
			(effects
				(font
					(size 1.016 1.016)
					(thickness 0.1524)
				)
			)
		)
		(duplicate_pad_numbers_are_jumpers no)
		(fp_line
			(start -0.508 -0.9398)
			(end -0.508 0.9398)
			(stroke
				(width 0.1524)
				(type default)
			)
			(layer "F.SilkS")
		)
		(fp_line
			(start 0.508 -0.9398)
			(end -0.508 -0.9398)
			(stroke
				(width 0.1524)
				(type default)
			)
			(layer "F.SilkS")
		)
		(fp_rect
			(start -0.508 0.9398)
			(end 0.508 -0.9398)
			(stroke
				(width 0)
				(type default)
			)
			(fill no)
			(layer "F.CrtYd")
		)
		(fp_rect
			(start -0.508 0.9398)
			(end 0.508 -0.9398)
			(stroke
				(width 0)
				(type default)
			)
			(fill no)
			(layer "F.Fab")
		)
		(pad "1" smd custom
			(at 0 -0.4445 270)
			(size 0.1397 0.1397)
			(layers "F.Cu" "F.Mask" "F.Paste")
			(net "NCSI_10G_TXEN")
			(options
				(clearance outline)
				(anchor circle)
			)
			(primitives
				(gr_poly
					(pts
						(arc
							(start -0.1778 -0.2794)
							(mid -0.249642 -0.249642)
							(end -0.2794 -0.1778)
						)
						(arc
							(start -0.2794 0.1778)
							(mid -0.249642 0.249642)
							(end -0.1778 0.2794)
						)
						(arc
							(start 0.1778 0.2794)
							(mid 0.249642 0.249642)
							(end 0.2794 0.1778)
						)
						(arc
							(start 0.2794 -0.1778)
							(mid 0.249642 -0.249642)
							(end 0.1778 -0.2794)
						)
					)
					(width 0)
					(fill yes)
				)
			)
		)
		(pad "2" smd custom
			(at 0 0.4445 270)
			(size 0.1397 0.1397)
			(layers "F.Cu" "F.Mask" "F.Paste")
			(net "NCSI_10G_TXEN_R")
			(options
				(clearance outline)
				(anchor circle)
			)
			(primitives
				(gr_poly
					(pts
						(arc
							(start -0.1778 -0.2794)
							(mid -0.249642 -0.249642)
							(end -0.2794 -0.1778)
						)
						(arc
							(start -0.2794 0.1778)
							(mid -0.249642 0.249642)
							(end -0.1778 0.2794)
						)
						(arc
							(start 0.1778 0.2794)
							(mid 0.249642 0.249642)
							(end 0.2794 0.1778)
						)
						(arc
							(start 0.2794 -0.1778)
							(mid 0.249642 -0.249642)
							(end 0.1778 -0.2794)
						)
					)
					(width 0)
					(fill yes)
				)
			)
		)
	)
)
